FILE_TYPE = CONNECTIVITY;
{Allegro Design Entry HDL 17.2-2016 S081 (4005846) 1/11/2022}
"PAGE_NUMBER" = 209;
0"NC";
1"P3V3_AUX\g";
2"P3V3_AUX\g";
3"P3V3_AUX\g";
4"GND\g";
5"GND\g";
6"GND\g";
7"GND\g";
8"FM_SLP_SUS_RSM_RST_N"CDS_PHYS_NET_NAME"FM_SLP_SUS_RSM_RST_N";
9"FM_DIS_PS_PWROK_DLY";
10"FM_RST_PERST_BIT2"CDS_PHYS_NET_NAME"FM_RST_PERST_BIT2";
11"FM_RST_PERST_BIT1"CDS_PHYS_NET_NAME"FM_RST_PERST_BIT1";
12"FM_RST_PERST_BIT0"CDS_PHYS_NET_NAME"FM_RST_PERST_BIT0";
13"PU_MAIN_FPGA_CONFIG_DONE"CDS_PHYS_NET_NAME"PU_MAIN_FPGA_CONFIG_DONE";
14"FM_PLD_HEARTBEAT_LVC3"CDS_PHYS_NET_NAME"FM_PLD_HEARTBEAT_LVC3";
15"ROT_P1_RST_IND_N_R"CDS_PHYS_NET_NAME"ROT_P1_RST_IND_N_R";
16"PWRGD_PCH_PWROK_R"CDS_PHYS_NET_NAME"PWRGD_PCH_PWROK_R";
17"FM_CPU_RMCA_CATERR_LVT3_R_N"CDS_PHYS_NET_NAME"FM_CPU_RMCA_CATERR_LVT3_R_N";
18"FM_SYS_THROTTLE_R_N"CDS_PHYS_NET_NAME"FM_SYS_THROTTLE_R_N";
19"FM_BMC_PWRBTN_N"CDS_PHYS_NET_NAME"FM_BMC_PWRBTN_N";
20"FM_ADR_TRIGGER_N"CDS_PHYS_NET_NAME"FM_ADR_TRIGGER_N";
21"JTAG_PLD_TDO_R"CDS_PHYS_NET_NAME"JTAG_PLD_TDO_R";
22"FM_PFR_DSW_PWROK_N"CDS_PHYS_NET_NAME"FM_PFR_DSW_PWROK_N";
23"FM_DIMM_12V_CPS_SX_N";
24"PWRGD_SYS_PWROK_R"CDS_PHYS_NET_NAME"PWRGD_SYS_PWROK_R";
%"UNIVERSAL_GND"
"1","(-3325,1825)","0","logical_power","I10";
;
ROOM"IO_SLOT"
CDS_LIB"logical_power"
HDL_POWER"GND";
"A"5;
%"Q_RES"
"2","(-3325,2050)","0","pure_quanta","I11";
;
PART_NUMBER"CS21002FB06"
VALUE"1K"
MATERIAL"EMPTY"
PACK_TYPE"0402LF"
WATTAGE"1/16W"
TOLERANCE"1%"
$LOCATION"R736"
CDS_LIB"pure_quanta"
CDS_LOCATION"R736"
$SEC"1"
CDS_SEC"1";
"A"
$PN"1"23;
"B"
$PN"2"5;
%"UNIVERSAL_POWER"
"1","(-3325,2775)","0","logical_power","I12";
;
HDL_POWER"P3V3_AUX"
CDS_LIB"logical_power";
"A"3;
%"Q_RES"
"2","(-3325,2525)","0","pure_quanta","I13";
;
PART_NUMBER"CS31002FB08"
TOLERANCE"1%"
VALUE"10K"
PACK_TYPE"0402LF"
MATERIAL"CHIP"
WATTAGE"1/16W"
$LOCATION"R735"
CDS_LIB"pure_quanta"
CDS_LOCATION"R735"
$SEC"1"
CDS_SEC"1";
"A"
$PN"1"3;
"B"
$PN"2"23;
%"Q_RES"
"1","(-1850,-500)","0","pure_quanta","I14";
;
PART_NUMBER"CS31002FB08"
MATERIAL"EMPTY"
VALUE"10K"
TOLERANCE"1%"
$LOCATION"R1660"
PACK_TYPE"0402LF"
WATTAGE"1/16W"
CDS_LIB"pure_quanta"
CDS_LOCATION"R1660"
$SEC"1"
CDS_SEC"1";
"B"
$PN"2"2;
"A"
$PN"1"8;
%"Q_RES"
"1","(-1850,-150)","0","pure_quanta","I15";
;
PART_NUMBER"CS31002FB08"
MATERIAL"EMPTY"
TOLERANCE"1%"
VALUE"10K"
$LOCATION"R1558"
PACK_TYPE"0402LF"
WATTAGE"1/16W"
CDS_LIB"pure_quanta"
CDS_LOCATION"R1558"
$SEC"1"
CDS_SEC"1";
"B"
$PN"2"2;
"A"
$PN"1"17;
%"Q_RES"
"1","(-1850,875)","0","pure_quanta","I16";
;
PART_NUMBER"CS31002FB08"
TOLERANCE"1%"
VALUE"10K"
MATERIAL"CHIP"
$LOCATION"R1401"
PACK_TYPE"0402LF"
WATTAGE"1/16W"
CDS_LIB"pure_quanta"
CDS_LOCATION"R1401"
$SEC"1"
CDS_SEC"1";
"B"
$PN"2"2;
"A"
$PN"1"13;
%"Q_RES"
"1","(-1850,1175)","0","pure_quanta","I17";
;
PART_NUMBER"CS31002FB08"
MATERIAL"CHIP"
TOLERANCE"1%"
VALUE"10K"
$LOCATION"R1399"
PACK_TYPE"0402LF"
WATTAGE"1/16W"
CDS_LIB"pure_quanta"
CDS_LOCATION"R1399"
$SEC"1"
CDS_SEC"1";
"B"
$PN"2"2;
"A"
$PN"1"22;
%"UNIVERSAL_POWER"
"1","(-1300,1700)","0","logical_power","I19";
;
HDL_POWER"P3V3_AUX"
CDS_LIB"logical_power";
"A"2;
%"UNIVERSAL_GND"
"1","(2325,-2850)","0","logical_power","I20";
;
ROOM"IO_SLOT"
CDS_LIB"logical_power"
HDL_POWER"GND";
"A"4;
%"Q_RES"
"1","(1775,-1825)","0","pure_quanta","I21";
;
PART_NUMBER"CS21002FB06"
VALUE"1K"
MATERIAL"EMPTY"
TOLERANCE"1%"
$LOCATION"R1494"
CDS_LIB"pure_quanta"
WATTAGE"1/16W"
PACK_TYPE"0402LF"
CDS_LOCATION"R1494"
$SEC"1"
CDS_SEC"1";
"B"
$PN"2"4;
"A"
$PN"1"9;
%"Q_RES"
"1","(1775,-1725)","0","pure_quanta","I22";
;
PART_NUMBER"CS31002FB08"
MATERIAL"EMPTY"
TOLERANCE"1%"
VALUE"10K"
$LOCATION"R1312"
CDS_LIB"pure_quanta"
PACK_TYPE"0402LF"
WATTAGE"1/16W"
CDS_LOCATION"R1312"
$SEC"1"
CDS_SEC"1";
"B"
$PN"2"4;
"A"
$PN"1"10;
%"Q_RES"
"1","(1775,-1625)","0","pure_quanta","I23";
;
PART_NUMBER"CS31002FB08"
MATERIAL"EMPTY"
VALUE"10K"
TOLERANCE"1%"
$LOCATION"R1308"
WATTAGE"1/16W"
PACK_TYPE"0402LF"
CDS_LIB"pure_quanta"
CDS_LOCATION"R1308"
$SEC"1"
CDS_SEC"1";
"B"
$PN"2"4;
"A"
$PN"1"11;
%"Q_RES"
"1","(1775,-1525)","0","pure_quanta","I24";
;
PART_NUMBER"CS31002FB08"
MATERIAL"EMPTY"
VALUE"10K"
TOLERANCE"1%"
$LOCATION"R1742"
PACK_TYPE"0402LF"
WATTAGE"1/16W"
CDS_LIB"pure_quanta"
CDS_LOCATION"R1742"
$SEC"1"
CDS_SEC"1";
"B"
$PN"2"4;
"A"
$PN"1"12;
%"Q_CAP"
"2","(-1525,-2325)","0","pure_quanta","I3";
;
PART_NUMBER"CH11006JB00"
VOLTAGE"50V"
PACK_TYPE"0402"
VALUE"100PF"
TOLERANCE"5%"
MATERIAL"NPO"
LOCATION"C1209"
CDS_LIB"pure_quanta"
$SEC"1"
CDS_SEC"1";
"A"
$PN"1"24;
"B"
$PN"2"6;
%"Q_RES"
"1","(1775,-1075)","0","pure_quanta","I35";
;
PART_NUMBER"CS31002FB08"
MATERIAL"CHIP"
TOLERANCE"1%"
VALUE"10K"
$LOCATION"R1492"
CDS_LIB"pure_quanta"
PACK_TYPE"0402LF"
WATTAGE"1/16W"
CDS_LOCATION"R1492"
$SEC"1"
CDS_SEC"1";
"B"
$PN"2"1;
"A"
$PN"1"9;
%"Q_RES"
"1","(1775,-975)","0","pure_quanta","I36";
;
PART_NUMBER"CS21002FB06"
VALUE"1K"
TOLERANCE"1%"
MATERIAL"CHIP"
$LOCATION"R1474"
PACK_TYPE"0402LF"
WATTAGE"1/16W"
CDS_LIB"pure_quanta"
CDS_LOCATION"R1474"
$SEC"1"
CDS_SEC"1";
"B"
$PN"2"1;
"A"
$PN"1"10;
%"Q_RES"
"1","(1775,-875)","0","pure_quanta","I37";
;
PART_NUMBER"CS21002FB06"
MATERIAL"CHIP"
TOLERANCE"1%"
VALUE"1K"
$LOCATION"R1473"
WATTAGE"1/16W"
PACK_TYPE"0402LF"
CDS_LIB"pure_quanta"
CDS_LOCATION"R1473"
$SEC"1"
CDS_SEC"1";
"B"
$PN"2"1;
"A"
$PN"1"11;
%"Q_RES"
"1","(1775,-775)","0","pure_quanta","I38";
;
PART_NUMBER"CS21002FB06"
VALUE"1K"
TOLERANCE"1%"
MATERIAL"CHIP"
$LOCATION"R1741"
WATTAGE"1/16W"
PACK_TYPE"0402LF"
CDS_LIB"pure_quanta"
CDS_LOCATION"R1741"
$SEC"1"
CDS_SEC"1";
"B"
$PN"2"1;
"A"
$PN"1"12;
%"Q_RES"
"1","(1775,-475)","0","pure_quanta","I39";
;
PART_NUMBER"CS31002FB08"
VALUE"10K"
TOLERANCE"1%"
MATERIAL"CHIP"
$LOCATION"R2244"
PACK_TYPE"0402LF"
WATTAGE"1/16W"
CDS_LIB"pure_quanta"
CDS_LOCATION"R2244"
$SEC"1"
CDS_SEC"1";
"B"
$PN"2"1;
"A"
$PN"1"15;
%"Q_CAP"
"2","(-1525,-2475)","0","pure_quanta","I4";
;
PART_NUMBER"CH11006JB00"
VALUE"100PF"
TOLERANCE"5%"
LOCATION"C1211"
CDS_LIB"pure_quanta"
MATERIAL"NPO"
PACK_TYPE"0402"
VOLTAGE"50V"
$SEC"1"
CDS_SEC"1";
"A"
$PN"1"16;
"B"
$PN"2"6;
%"Q_RES"
"1","(1775,-350)","0","pure_quanta","I40";
;
PART_NUMBER"CS31002FB08"
VALUE"10K"
TOLERANCE"1%"
MATERIAL"EMPTY"
$LOCATION"R139"
CDS_LIB"pure_quanta"
WATTAGE"1/16W"
PACK_TYPE"0402LF"
CDS_LOCATION"R139"
$SEC"1"
CDS_SEC"1";
"B"
$PN"2"1;
"A"
$PN"1"19;
%"Q_RES"
"1","(1775,-50)","0","pure_quanta","I41";
;
PART_NUMBER"CS31002FB08"
MATERIAL"EMPTY"
TOLERANCE"1%"
VALUE"10K"
$LOCATION"R1440"
CDS_LIB"pure_quanta"
WATTAGE"1/16W"
PACK_TYPE"0402LF"
CDS_LOCATION"R1440"
$SEC"1"
CDS_SEC"1";
"B"
$PN"2"1;
"A"
$PN"1"21;
%"Q_RES"
"1","(1775,400)","0","pure_quanta","I42";
;
PART_NUMBER"CS31002FB08"
TOLERANCE"1%"
MATERIAL"CHIP"
VALUE"10K"
$LOCATION"R1437"
PACK_TYPE"0402LF"
WATTAGE"1/16W"
CDS_LIB"pure_quanta"
CDS_LOCATION"R1437"
$SEC"1"
CDS_SEC"1";
"B"
$PN"2"1;
"A"
$PN"1"14;
%"Q_RES"
"1","(1775,700)","0","pure_quanta","I43";
;
PART_NUMBER"CS31002FB08"
VALUE"10K"
TOLERANCE"1%"
MATERIAL"CHIP"
$LOCATION"R1435"
CDS_LIB"pure_quanta"
WATTAGE"1/16W"
PACK_TYPE"0402LF"
CDS_LOCATION"R1435"
$SEC"1"
CDS_SEC"1";
"B"
$PN"2"1;
"A"
$PN"1"20;
%"Q_RES"
"1","(1775,850)","0","pure_quanta","I44";
;
PART_NUMBER"CS31002FB08"
WATTAGE"1/16W"
VALUE"10K"
MATERIAL"CHIP"
TOLERANCE"1%"
PACK_TYPE"0402LF"
$LOCATION"R1434"
CDS_LIB"pure_quanta"
CDS_LOCATION"R1434"
$SEC"1"
CDS_SEC"1";
"B"
$PN"2"1;
"A"
$PN"1"18;
%"UNIVERSAL_POWER"
"1","(2325,1075)","0","logical_power","I45";
;
HDL_POWER"P3V3_AUX"
CDS_LIB"logical_power";
"A"1;
%"Q_RES"
"2","(-2325,-850)","0","pure_quanta","I46";
;
PART_NUMBER"CS31002FB08"
PACK_TYPE"0402LF"
MATERIAL"CHIP"
WATTAGE"1/16W"
TOLERANCE"1%"
VALUE"10K"
$LOCATION"R4674"
CDS_LIB"pure_quanta"
CDS_LOCATION"R4674"
$SEC"1"
CDS_SEC"1";
"A"
$PN"1"8;
"B"
$PN"2"7;
%"UNIVERSAL_GND"
"1","(-2325,-1050)","0","logical_power","I47";
;
ROOM"IO_SLOT"
CDS_LIB"logical_power"
HDL_POWER"GND";
"A"7;
%"UNIVERSAL_GND"
"1","(-975,-2975)","0","logical_power","I5";
;
ROOM"IO_SLOT"
CDS_LIB"logical_power"
HDL_POWER"GND";
"A"6;
END.
